FILE_TYPE = CONNECTIVITY;
{Allegro Design Entry HDL 17.2-2016 S067 (3860444) 4/26/2020}
"PAGE_NUMBER" = 33;
0"NC";
1"SG\g";
2"SG\g";
3"SG\g";
4"SG\g";
5"SG\g";
6"SG\g";
%"MEC_MTH8"
"1","(-3400,6550)","0","mech","I1";
;
$LOCATION"ME11"
CDS_SEC"1"
$SEC"1"
CDS_LOCATION"ME11"
CDS_LMAN_SYM_OUTLINE"0,0,100,-800"
BOM_IGNORE"TRUE"
CDS_LIB"mech"
JEDEC_TYPE"MTH125C236N_V8";
"8"
$PN"8"3;
"7"
$PN"7"3;
"6"
$PN"6"3;
"5"
$PN"5"3;
"4"
$PN"4"3;
"3"
$PN"3"3;
"2"
$PN"2"3;
"1"
$PN"1"3;
%"MEC_NPTH"
"1","(-5250,7550)","0","mech","I120";
;
$LOCATION"ME8"
CDS_LOCATION"ME8"
JEDEC_TYPE"MTH100C240N"
BOM_IGNORE"TRUE"
CDS_LMAN_SYM_OUTLINE"-100,100,100,-100"
CDS_LIB"mech";
%"MEC_NPTH"
"1","(-5750,7550)","0","mech","I121";
;
$LOCATION"ME7"
CDS_LOCATION"ME7"
JEDEC_TYPE"MTH100C240N"
BOM_IGNORE"TRUE"
CDS_LMAN_SYM_OUTLINE"-100,100,100,-100"
CDS_LIB"mech";
%"MEC_NPTH"
"1","(-6250,7550)","0","mech","I122";
;
$LOCATION"ME6"
CDS_LOCATION"ME6"
JEDEC_TYPE"MTH100C240N"
BOM_IGNORE"TRUE"
CDS_LMAN_SYM_OUTLINE"-100,100,100,-100"
CDS_LIB"mech";
%"MEC_NPTH"
"1","(-6750,7550)","0","mech","I123";
;
$LOCATION"ME5"
CDS_LOCATION"ME5"
JEDEC_TYPE"MTH100C240N"
CDS_LIB"mech"
BOM_IGNORE"TRUE"
CDS_LMAN_SYM_OUTLINE"-100,100,100,-100";
%"GND_SG"
"1","(-8950,5950)","0","cls","I124";
;
HDL_POWER"SG"
CDS_LIB"cls"
CDS_LMAN_SYM_OUTLINE"0,0,100,-50"
VOLTAGE"0"
BODY_TYPE"PLUMBING";
"SGND"6;
%"NUT"
"1","(-9350,6850)","2","mech","I125";
;
CDS_LOCATION"ME3"
CLS_PN"G340-10437-01"
LOCATION"ME3"
PART_NUMBER"SMTSO-440-12ET"
CDS_SEC"1"
$SEC"1"
CDS_LIB"mech"
CDS_LMAN_SYM_OUTLINE"-50,50,50,-50";
"1 \B"
$PN"1"6;
%"NUT"
"1","(-9350,6150)","2","mech","I126";
;
CDS_LOCATION"ME4"
CLS_PN"G340-10437-01"
PART_NUMBER"SMTSO-440-12ET"
LOCATION"ME4"
CDS_SEC"1"
$SEC"1"
CDS_LMAN_SYM_OUTLINE"-50,50,50,-50"
CDS_LIB"mech";
"1 \B"
$PN"1"6;
%"NUT"
"1","(-11400,6850)","2","mech","I127";
;
CDS_LOCATION"ME1"
CLS_PN"G340-10437-01"
LOCATION"ME1"
PART_NUMBER"SMTSO-440-12ET"
CDS_SEC"1"
$SEC"1"
CDS_LIB"mech"
CDS_LMAN_SYM_OUTLINE"-50,50,50,-50";
"1 \B"
$PN"1"5;
%"GND_SG"
"1","(-11000,5950)","0","cls","I128";
;
HDL_POWER"SG"
BODY_TYPE"PLUMBING"
CDS_LIB"cls"
CDS_LMAN_SYM_OUTLINE"0,0,100,-50"
VOLTAGE"0";
"SGND"5;
%"NUT"
"1","(-11400,6150)","2","mech","I129";
;
CDS_LOCATION"ME2"
CLS_PN"G340-10437-01"
LOCATION"ME2"
PART_NUMBER"SMTSO-440-12ET"
CDS_SEC"1"
$SEC"1"
CDS_LMAN_SYM_OUTLINE"-50,50,50,-50"
CDS_LIB"mech";
"1 \B"
$PN"1"5;
%"SOLDER_PREFORM"
"1","(-12750,2100)","0","mech","I130";
;
CDS_LOCATION"SP4"
CLS_PN"G380-10015-01"
LOCATION"SP4"
CDS_LMAN_SYM_OUTLINE"0,0,250,-200"
CDS_LIB"mech"
$SEC"1"
CDS_SEC"1";
"2"
$PN"2"0;
"1"
$PN"1"0;
%"SOLDER_PREFORM"
"1","(-11850,2100)","0","mech","I131";
;
CDS_LOCATION"SP5"
CLS_PN"G380-10015-01"
LOCATION"SP5"
CDS_LMAN_SYM_OUTLINE"0,0,250,-200"
CDS_LIB"mech"
$SEC"1"
CDS_SEC"1";
"2"
$PN"2"0;
"1"
$PN"1"0;
%"SOLDER_PREFORM"
"1","(-10100,2100)","0","mech","I132";
;
CDS_LOCATION"SP7"
CLS_PN"G380-10015-01"
LOCATION"SP7"
CDS_LIB"mech"
CDS_LMAN_SYM_OUTLINE"0,0,250,-200"
$SEC"1"
CDS_SEC"1";
"2"
$PN"2"0;
"1"
$PN"1"0;
%"SOLDER_PREFORM"
"1","(-11000,2100)","0","mech","I133";
;
CDS_LOCATION"SP6"
LOCATION"SP6"
CLS_PN"G380-10015-01"
CDS_LIB"mech"
CDS_LMAN_SYM_OUTLINE"0,0,250,-200"
$SEC"1"
CDS_SEC"1";
"2"
$PN"2"0;
"1"
$PN"1"0;
%"SOLDER_PREFORM"
"1","(-9150,2100)","0","mech","I134";
;
CDS_LOCATION"SP8"
LOCATION"SP8"
CLS_PN"G380-10015-01"
CDS_LMAN_SYM_OUTLINE"0,0,250,-200"
CDS_LIB"mech"
$SEC"1"
CDS_SEC"1";
"2"
$PN"2"0;
"1"
$PN"1"0;
%"SOLDER_PREFORM"
"1","(-8250,2100)","0","mech","I135";
;
CDS_LOCATION"SP9"
LOCATION"SP9"
CLS_PN"G380-10015-01"
CDS_LMAN_SYM_OUTLINE"0,0,250,-200"
CDS_LIB"mech"
$SEC"1"
CDS_SEC"1";
"2"
$PN"2"0;
"1"
$PN"1"0;
%"SOLDER_PREFORM"
"1","(-6500,2100)","0","mech","I136";
;
CDS_LOCATION"SP11"
LOCATION"SP11"
CLS_PN"G380-10015-01"
CDS_LIB"mech"
CDS_LMAN_SYM_OUTLINE"0,0,250,-200"
$SEC"1"
CDS_SEC"1";
"2"
$PN"2"0;
"1"
$PN"1"0;
%"SOLDER_PREFORM"
"1","(-7400,2100)","0","mech","I137";
;
CDS_LOCATION"SP10"
CLS_PN"G380-10015-01"
LOCATION"SP10"
CDS_LIB"mech"
CDS_LMAN_SYM_OUTLINE"0,0,250,-200"
$SEC"1"
CDS_SEC"1";
"2"
$PN"2"0;
"1"
$PN"1"0;
%"SOLDER_PREFORM"
"1","(-2900,2100)","0","mech","I138";
;
CDS_LOCATION"SP15"
LOCATION"SP15"
CLS_PN"G380-10015-01"
CDS_LIB"mech"
CDS_LMAN_SYM_OUTLINE"0,0,250,-200"
$SEC"1"
CDS_SEC"1";
"2"
$PN"2"0;
"1"
$PN"1"0;
%"SOLDER_PREFORM"
"1","(-3800,2100)","0","mech","I139";
;
CDS_LOCATION"SP14"
CLS_PN"G380-10015-01"
LOCATION"SP14"
CDS_LIB"mech"
CDS_LMAN_SYM_OUTLINE"0,0,250,-200"
$SEC"1"
CDS_SEC"1";
"2"
$PN"2"0;
"1"
$PN"1"0;
%"SOLDER_PREFORM"
"1","(-4650,2100)","0","mech","I140";
;
CDS_LOCATION"SP13"
LOCATION"SP13"
CLS_PN"G380-10015-01"
CDS_LMAN_SYM_OUTLINE"0,0,250,-200"
CDS_LIB"mech"
$SEC"1"
CDS_SEC"1";
"2"
$PN"2"0;
"1"
$PN"1"0;
%"SOLDER_PREFORM"
"1","(-5550,2100)","0","mech","I141";
;
CDS_LOCATION"SP12"
LOCATION"SP12"
CLS_PN"G380-10015-01"
CDS_LMAN_SYM_OUTLINE"0,0,250,-200"
CDS_LIB"mech"
$SEC"1"
CDS_SEC"1";
"2"
$PN"2"0;
"1"
$PN"1"0;
%"SOLDER_PREFORM"
"1","(-11850,1600)","0","mech","I142";
;
CDS_LOCATION"SP17"
LOCATION"SP17"
CLS_PN"G380-10015-01"
CDS_LMAN_SYM_OUTLINE"0,0,250,-200"
CDS_LIB"mech"
$SEC"1"
CDS_SEC"1";
"2"
$PN"2"0;
"1"
$PN"1"0;
%"SOLDER_PREFORM"
"1","(-2900,1600)","0","mech","I143";
;
CDS_LOCATION"SP27"
LOCATION"SP27"
CLS_PN"G380-10015-01"
CDS_LIB"mech"
CDS_LMAN_SYM_OUTLINE"0,0,250,-200"
$SEC"1"
CDS_SEC"1";
"2"
$PN"2"0;
"1"
$PN"1"0;
%"SOLDER_PREFORM"
"1","(-3800,1600)","0","mech","I144";
;
CDS_LOCATION"SP26"
LOCATION"SP26"
CLS_PN"G380-10015-01"
CDS_LIB"mech"
CDS_LMAN_SYM_OUTLINE"0,0,250,-200"
$SEC"1"
CDS_SEC"1";
"2"
$PN"2"0;
"1"
$PN"1"0;
%"SOLDER_PREFORM"
"1","(-4650,1600)","0","mech","I145";
;
CDS_LOCATION"SP25"
CLS_PN"G380-10015-01"
LOCATION"SP25"
CDS_LMAN_SYM_OUTLINE"0,0,250,-200"
CDS_LIB"mech"
$SEC"1"
CDS_SEC"1";
"2"
$PN"2"0;
"1"
$PN"1"0;
%"SOLDER_PREFORM"
"1","(-5550,1600)","0","mech","I146";
;
CDS_LOCATION"SP24"
LOCATION"SP24"
CLS_PN"G380-10015-01"
CDS_LMAN_SYM_OUTLINE"0,0,250,-200"
CDS_LIB"mech"
$SEC"1"
CDS_SEC"1";
"2"
$PN"2"0;
"1"
$PN"1"0;
%"SOLDER_PREFORM"
"1","(-6500,1600)","0","mech","I147";
;
CDS_LOCATION"SP23"
CLS_PN"G380-10015-01"
LOCATION"SP23"
CDS_LIB"mech"
CDS_LMAN_SYM_OUTLINE"0,0,250,-200"
$SEC"1"
CDS_SEC"1";
"2"
$PN"2"0;
"1"
$PN"1"0;
%"SOLDER_PREFORM"
"1","(-7400,1600)","0","mech","I148";
;
CDS_LOCATION"SP22"
LOCATION"SP22"
CLS_PN"G380-10015-01"
CDS_LIB"mech"
CDS_LMAN_SYM_OUTLINE"0,0,250,-200"
$SEC"1"
CDS_SEC"1";
"2"
$PN"2"0;
"1"
$PN"1"0;
%"SOLDER_PREFORM"
"1","(-9150,1600)","0","mech","I149";
;
CDS_LOCATION"SP20"
LOCATION"SP20"
CLS_PN"G380-10015-01"
CDS_LMAN_SYM_OUTLINE"0,0,250,-200"
CDS_LIB"mech"
$SEC"1"
CDS_SEC"1";
"2"
$PN"2"0;
"1"
$PN"1"0;
%"SOLDER_PREFORM"
"1","(-8250,1600)","0","mech","I150";
;
CDS_LOCATION"SP21"
CLS_PN"G380-10015-01"
LOCATION"SP21"
CDS_LMAN_SYM_OUTLINE"0,0,250,-200"
CDS_LIB"mech"
$SEC"1"
CDS_SEC"1";
"2"
$PN"2"0;
"1"
$PN"1"0;
%"SOLDER_PREFORM"
"1","(-10100,1600)","0","mech","I151";
;
CDS_LOCATION"SP19"
CLS_PN"G380-10015-01"
LOCATION"SP19"
CDS_LMAN_SYM_OUTLINE"0,0,250,-200"
CDS_LIB"mech"
$SEC"1"
CDS_SEC"1";
"2"
$PN"2"0;
"1"
$PN"1"0;
%"SOLDER_PREFORM"
"1","(-11000,1600)","0","mech","I152";
;
CDS_LOCATION"SP18"
LOCATION"SP18"
CLS_PN"G380-10015-01"
CDS_LIB"mech"
CDS_LMAN_SYM_OUTLINE"0,0,250,-200"
$SEC"1"
CDS_SEC"1";
"2"
$PN"2"0;
"1"
$PN"1"0;
%"SOLDER_PREFORM"
"1","(-12750,1600)","0","mech","I153";
;
CDS_LOCATION"SP16"
LOCATION"SP16"
CLS_PN"G380-10015-01"
CDS_LMAN_SYM_OUTLINE"0,0,250,-200"
CDS_LIB"mech"
$SEC"1"
CDS_SEC"1";
"2"
$PN"2"0;
"1"
$PN"1"0;
%"SOLDER_PREFORM"
"1","(-11900,550)","0","mech","I155";
;
CDS_LOCATION"SP41"
LOCATION"SP41"
CLS_PN"G380-10015-01"
CDS_LIB"mech"
CDS_LMAN_SYM_OUTLINE"0,0,250,-200"
$SEC"1"
CDS_SEC"1";
"2"
$PN"2"0;
"1"
$PN"1"0;
%"SOLDER_PREFORM"
"1","(-3800,1100)","0","mech","I159";
;
CDS_LOCATION"SP38"
LOCATION"SP38"
CLS_PN"G380-10015-01"
CDS_LIB"mech"
CDS_LMAN_SYM_OUTLINE"0,0,250,-200"
$SEC"1"
CDS_SEC"1";
"2"
$PN"2"0;
"1"
$PN"1"0;
%"SOLDER_PREFORM"
"1","(-4700,1100)","0","mech","I161";
;
CDS_LOCATION"SP37"
LOCATION"SP37"
CLS_PN"G380-10015-01"
CDS_LIB"mech"
CDS_LMAN_SYM_OUTLINE"0,0,250,-200"
$SEC"1"
CDS_SEC"1";
"2"
$PN"2"0;
"1"
$PN"1"0;
%"SOLDER_PREFORM"
"1","(-5550,1100)","0","mech","I163";
;
CDS_LOCATION"SP36"
LOCATION"SP36"
CLS_PN"G380-10015-01"
CDS_LMAN_SYM_OUTLINE"0,0,250,-200"
CDS_LIB"mech"
$SEC"1"
CDS_SEC"1";
"2"
$PN"2"0;
"1"
$PN"1"0;
%"SOLDER_PREFORM"
"1","(-6450,1100)","0","mech","I165";
;
CDS_LOCATION"SP35"
LOCATION"SP35"
CLS_PN"G380-10015-01"
CDS_LMAN_SYM_OUTLINE"0,0,250,-200"
CDS_LIB"mech"
$SEC"1"
CDS_SEC"1";
"2"
$PN"2"0;
"1"
$PN"1"0;
%"SOLDER_PREFORM"
"1","(-7400,1100)","0","mech","I167";
;
CDS_LOCATION"SP34"
LOCATION"SP34"
CLS_PN"G380-10015-01"
CDS_LIB"mech"
CDS_LMAN_SYM_OUTLINE"0,0,250,-200"
$SEC"1"
CDS_SEC"1";
"2"
$PN"2"0;
"1"
$PN"1"0;
%"SOLDER_PREFORM"
"1","(-8300,1100)","0","mech","I169";
;
CDS_LOCATION"SP33"
LOCATION"SP33"
CLS_PN"G380-10015-01"
CDS_LIB"mech"
CDS_LMAN_SYM_OUTLINE"0,0,250,-200"
$SEC"1"
CDS_SEC"1";
"2"
$PN"2"0;
"1"
$PN"1"0;
%"SOLDER_PREFORM"
"1","(-9150,1100)","0","mech","I171";
;
CDS_LOCATION"SP32"
LOCATION"SP32"
CLS_PN"G380-10015-01"
CDS_LMAN_SYM_OUTLINE"0,0,250,-200"
CDS_LIB"mech"
$SEC"1"
CDS_SEC"1";
"2"
$PN"2"0;
"1"
$PN"1"0;
%"SOLDER_PREFORM"
"1","(-10050,1100)","0","mech","I172";
;
CDS_LOCATION"SP31"
LOCATION"SP31"
CLS_PN"G380-10015-01"
CDS_LMAN_SYM_OUTLINE"0,0,250,-200"
CDS_LIB"mech"
$SEC"1"
CDS_SEC"1";
"2"
$PN"2"0;
"1"
$PN"1"0;
%"SOLDER_PREFORM"
"1","(-11000,1100)","0","mech","I173";
;
CDS_LOCATION"SP30"
LOCATION"SP30"
CLS_PN"G380-10015-01"
CDS_LIB"mech"
CDS_LMAN_SYM_OUTLINE"0,0,250,-200"
$SEC"1"
CDS_SEC"1";
"2"
$PN"2"0;
"1"
$PN"1"0;
%"SOLDER_PREFORM"
"1","(-11900,1100)","0","mech","I174";
;
CDS_LOCATION"SP29"
CLS_PN"G380-10015-01"
LOCATION"SP29"
CDS_LIB"mech"
CDS_LMAN_SYM_OUTLINE"0,0,250,-200"
$SEC"1"
CDS_SEC"1";
"2"
$PN"2"0;
"1"
$PN"1"0;
%"SOLDER_PREFORM"
"1","(-12750,1100)","0","mech","I175";
;
CDS_LOCATION"SP28"
LOCATION"SP28"
CLS_PN"G380-10015-01"
CDS_LMAN_SYM_OUTLINE"0,0,250,-200"
CDS_LIB"mech"
$SEC"1"
CDS_SEC"1";
"2"
$PN"2"0;
"1"
$PN"1"0;
%"SOLDER_PREFORM"
"1","(-12750,550)","0","mech","I176";
;
CDS_LOCATION"SP40"
CLS_PN"G380-10015-01"
LOCATION"SP40"
CDS_LMAN_SYM_OUTLINE"0,0,250,-200"
CDS_LIB"mech"
$SEC"1"
CDS_SEC"1";
"2"
$PN"2"0;
"1"
$PN"1"0;
%"SOLDER_PREFORM"
"1","(-2900,1100)","0","mech","I177";
;
CDS_LOCATION"SP39"
LOCATION"SP39"
CLS_PN"G380-10015-01"
CDS_LMAN_SYM_OUTLINE"0,0,250,-200"
CDS_LIB"mech"
$SEC"1"
CDS_SEC"1";
"2"
$PN"2"0;
"1"
$PN"1"0;
%"MEC_MTH8"
"1","(-1850,6550)","0","mech","I2";
;
$LOCATION"ME12"
CDS_SEC"1"
$SEC"1"
CDS_LOCATION"ME12"
CDS_LIB"mech"
CDS_LMAN_SYM_OUTLINE"0,0,100,-800"
JEDEC_TYPE"MTH125C236N_V8"
BOM_IGNORE"TRUE";
"8"
$PN"8"4;
"7"
$PN"7"4;
"6"
$PN"6"4;
"5"
$PN"5"4;
"4"
$PN"4"4;
"3"
$PN"3"4;
"2"
$PN"2"4;
"1"
$PN"1"4;
%"GND_SG"
"1","(-2200,5650)","0","cls","I3";
;
HDL_POWER"SG"
BODY_TYPE"PLUMBING"
CDS_LIB"cls"
CDS_LMAN_SYM_OUTLINE"0,0,100,-50";
"SGND"4;
%"GND_SG"
"1","(-3750,5650)","0","cls","I4";
;
HDL_POWER"SG"
BODY_TYPE"PLUMBING"
CDS_LMAN_SYM_OUTLINE"0,0,100,-50"
CDS_LIB"cls";
"SGND"3;
%"NULL"
"1","(-12750,3850)","0","mech","I47";
;
CDS_LOCATION"SP54"
LOCATION"SP54"
CLS_PN"G380-10013-01"
CDS_LIB"mech"
CDS_LMAN_SYM_OUTLINE"0,0,300,-300";
%"NULL"
"1","(-11800,3850)","0","mech","I48";
;
CDS_LOCATION"SP55"
CLS_PN"G380-10013-01"
LOCATION"SP55"
CDS_LIB"mech"
CDS_LMAN_SYM_OUTLINE"0,0,300,-300";
%"NULL"
"1","(-9900,3850)","0","mech","I49";
;
CDS_LOCATION"SP57"
CLS_PN"G380-10013-01"
LOCATION"SP57"
CDS_LIB"mech"
CDS_LMAN_SYM_OUTLINE"0,0,300,-300";
%"MEC_MTH8"
"1","(-4950,6550)","0","mech","I5";
;
$LOCATION"ME10"
CDS_SEC"1"
$SEC"1"
CDS_LOCATION"ME10"
CDS_LIB"mech"
CDS_LMAN_SYM_OUTLINE"0,0,100,-800"
JEDEC_TYPE"MTH125C236N_V8"
BOM_IGNORE"TRUE";
"8"
$PN"8"2;
"7"
$PN"7"2;
"6"
$PN"6"2;
"5"
$PN"5"2;
"4"
$PN"4"2;
"3"
$PN"3"2;
"2"
$PN"2"2;
"1"
$PN"1"2;
%"NULL"
"1","(-10850,3850)","0","mech","I50";
;
CDS_LOCATION"SP56"
LOCATION"SP56"
CLS_PN"G380-10013-01"
CDS_LIB"mech"
CDS_LMAN_SYM_OUTLINE"0,0,300,-300";
%"NULL"
"1","(-6100,3850)","0","mech","I51";
;
CDS_LOCATION"SP61"
CLS_PN"G380-10013-01"
LOCATION"SP61"
CDS_LIB"mech"
CDS_LMAN_SYM_OUTLINE"0,0,300,-300";
%"NULL"
"1","(-7050,3850)","0","mech","I52";
;
CDS_LOCATION"SP60"
LOCATION"SP60"
CLS_PN"G380-10013-01"
CDS_LIB"mech"
CDS_LMAN_SYM_OUTLINE"0,0,300,-300";
%"NULL"
"1","(-8000,3850)","0","mech","I53";
;
CDS_LOCATION"SP59"
CLS_PN"G380-10013-01"
LOCATION"SP59"
CDS_LIB"mech"
CDS_LMAN_SYM_OUTLINE"0,0,300,-300";
%"NULL"
"1","(-8950,3850)","0","mech","I54";
;
CDS_LOCATION"SP58"
LOCATION"SP58"
CLS_PN"G380-10013-01"
CDS_LIB"mech"
CDS_LMAN_SYM_OUTLINE"0,0,300,-300";
%"NULL"
"1","(-5150,3850)","0","mech","I55";
;
CDS_LOCATION"SP62"
LOCATION"SP62"
CLS_PN"G380-10013-01"
CDS_LMAN_SYM_OUTLINE"0,0,300,-300"
CDS_LIB"mech";
%"NULL"
"1","(-4200,3850)","0","mech","I56";
;
CDS_LOCATION"SP63"
CLS_PN"G380-10013-01"
LOCATION"SP63"
CDS_LMAN_SYM_OUTLINE"0,0,300,-300"
CDS_LIB"mech";
%"NULL"
"1","(-3250,3850)","0","mech","I57";
;
CDS_LOCATION"SP64"
LOCATION"SP64"
CLS_PN"G380-10013-01"
CDS_LMAN_SYM_OUTLINE"0,0,300,-300"
CDS_LIB"mech";
%"NULL"
"1","(-2300,3850)","0","mech","I58";
;
CDS_LOCATION"SP65"
LOCATION"SP65"
CLS_PN"G380-10013-01"
CDS_LMAN_SYM_OUTLINE"0,0,300,-300"
CDS_LIB"mech";
%"NULL"
"1","(-8000,4400)","0","mech","I59";
;
CDS_LOCATION"SP47"
CLS_PN"G380-10013-01"
LOCATION"SP47"
CDS_LMAN_SYM_OUTLINE"0,0,300,-300"
CDS_LIB"mech";
%"GND_SG"
"1","(-5300,5650)","0","cls","I6";
;
HDL_POWER"SG"
CDS_LMAN_SYM_OUTLINE"0,0,100,-50"
CDS_LIB"cls"
BODY_TYPE"PLUMBING";
"SGND"2;
%"NULL"
"1","(-7050,4400)","0","mech","I60";
;
CDS_LOCATION"SP48"
CLS_PN"G380-10013-01"
LOCATION"SP48"
CDS_LMAN_SYM_OUTLINE"0,0,300,-300"
CDS_LIB"mech";
%"NULL"
"1","(-2300,4400)","0","mech","I61";
;
CDS_LOCATION"SP53"
CLS_PN"G380-10013-01"
LOCATION"SP53"
CDS_LIB"mech"
CDS_LMAN_SYM_OUTLINE"0,0,300,-300";
%"NULL"
"1","(-3250,4400)","0","mech","I62";
;
CDS_LOCATION"SP52"
CLS_PN"G380-10013-01"
LOCATION"SP52"
CDS_LIB"mech"
CDS_LMAN_SYM_OUTLINE"0,0,300,-300";
%"NULL"
"1","(-4200,4400)","0","mech","I63";
;
CDS_LOCATION"SP51"
CLS_PN"G380-10013-01"
LOCATION"SP51"
CDS_LIB"mech"
CDS_LMAN_SYM_OUTLINE"0,0,300,-300";
%"NULL"
"1","(-5150,4400)","0","mech","I64";
;
CDS_LOCATION"SP50"
LOCATION"SP50"
CLS_PN"G380-10013-01"
CDS_LIB"mech"
CDS_LMAN_SYM_OUTLINE"0,0,300,-300";
%"NULL"
"1","(-6100,4400)","0","mech","I65";
;
CDS_LOCATION"SP49"
CLS_PN"G380-10013-01"
LOCATION"SP49"
CDS_LMAN_SYM_OUTLINE"0,0,300,-300"
CDS_LIB"mech";
%"NULL"
"1","(-8950,4400)","0","mech","I66";
;
CDS_LOCATION"SP46"
CLS_PN"G380-10013-01"
LOCATION"SP46"
CDS_LMAN_SYM_OUTLINE"0,0,300,-300"
CDS_LIB"mech";
%"NULL"
"1","(-9900,4400)","0","mech","I67";
;
CDS_LOCATION"SP45"
CLS_PN"G380-10013-01"
LOCATION"SP45"
CDS_LMAN_SYM_OUTLINE"0,0,300,-300"
CDS_LIB"mech";
%"NULL"
"1","(-10850,4400)","0","mech","I68";
;
CDS_LOCATION"SP44"
CLS_PN"G380-10013-01"
LOCATION"SP44"
CDS_LMAN_SYM_OUTLINE"0,0,300,-300"
CDS_LIB"mech";
%"NULL"
"1","(-11800,4400)","0","mech","I69";
;
CDS_LOCATION"SP43"
CLS_PN"G380-10013-01"
LOCATION"SP43"
CDS_LMAN_SYM_OUTLINE"0,0,300,-300"
CDS_LIB"mech";
%"MEC_MTH8"
"1","(-6500,6550)","0","mech","I7";
;
$LOCATION"ME9"
CDS_SEC"1"
$SEC"1"
CDS_LOCATION"ME9"
BOM_IGNORE"TRUE"
JEDEC_TYPE"MTH125C236N_V8"
CDS_LMAN_SYM_OUTLINE"0,0,100,-800"
CDS_LIB"mech";
"8"
$PN"8"1;
"7"
$PN"7"1;
"6"
$PN"6"1;
"5"
$PN"5"1;
"4"
$PN"4"1;
"3"
$PN"3"1;
"2"
$PN"2"1;
"1"
$PN"1"1;
%"NULL"
"1","(-12750,4400)","0","mech","I70";
;
CDS_LOCATION"SP42"
CLS_PN"G380-10013-01"
LOCATION"SP42"
CDS_LMAN_SYM_OUTLINE"0,0,300,-300"
CDS_LIB"mech";
%"GND_SG"
"1","(-6850,5650)","0","cls","I8";
;
HDL_POWER"SG"
BODY_TYPE"PLUMBING"
CDS_LMAN_SYM_OUTLINE"0,0,100,-50"
CDS_LIB"cls";
"SGND"1;
%"NULL"
"1","(-8000,3300)","0","mech","I83";
;
CDS_LOCATION"SP71"
LOCATION"SP71"
CLS_PN"G380-10013-01"
CDS_LMAN_SYM_OUTLINE"0,0,300,-300"
CDS_LIB"mech";
%"NULL"
"1","(-8950,3300)","0","mech","I84";
;
CDS_LOCATION"SP70"
LOCATION"SP70"
CLS_PN"G380-10013-01"
CDS_LMAN_SYM_OUTLINE"0,0,300,-300"
CDS_LIB"mech";
%"NULL"
"1","(-9900,3300)","0","mech","I85";
;
CDS_LOCATION"SP69"
CLS_PN"G380-10013-01"
LOCATION"SP69"
CDS_LMAN_SYM_OUTLINE"0,0,300,-300"
CDS_LIB"mech";
%"NULL"
"1","(-10850,3300)","0","mech","I89";
;
CDS_LOCATION"SP68"
LOCATION"SP68"
CLS_PN"G380-10013-01"
CDS_LMAN_SYM_OUTLINE"0,0,300,-300"
CDS_LIB"mech";
%"NULL"
"1","(-11800,3300)","0","mech","I90";
;
CDS_LOCATION"SP67"
CLS_PN"G380-10013-01"
LOCATION"SP67"
CDS_LMAN_SYM_OUTLINE"0,0,300,-300"
CDS_LIB"mech";
%"NULL"
"1","(-12750,3300)","0","mech","I93";
;
CDS_LOCATION"SP66"
LOCATION"SP66"
CLS_PN"G380-10013-01"
CDS_LMAN_SYM_OUTLINE"0,0,300,-300"
CDS_LIB"mech";
END.
